# S9S_MB_2U (Grand Teton) — schematic netlist excerpt (pin names and nets, part order shuffled) for the footprints in the layout excerpt that follows; sources: Cadence DE-HDL packaged netlist, KiCad conversion of 03242023_DA0F0TMBIJ0_F0T_Motherboard_J_brd_V01_OCP.brd

C2040  Q_CAP  0.1UF 25V 10% X7R  pkg 0402  page 152 : A = P3V3_AUX_USB_HUB ; B = GND
PR293  Q_RES  2.2 1% CHIP  pkg 0402LF  page 287 : A = PVCCIN_CPU1_PVCC ; B = PVCCIN_CPU1_VDD6

(kicad_pcb
	(version 20260206)
	(generator "pcbnew")
	(generator_version "10.0")
	(general
		(thickness 1.6)
		(legacy_teardrops no)
	)
	(paper "A4")
	(title_block
		(title "03242023_DA0F0TMBIJ0_F0T_Motherboard_J_brd_V01_OCP.brd")
		(comment 1 "Grand Teton / footprints 4754-4755 of 6105")
	)
	(layers
		(0 "F.Cu" signal "TOP")
		(4 "In1.Cu" signal "GND")
		(6 "In2.Cu" signal "IN1")
		(8 "In3.Cu" signal "GND1")
		(10 "In4.Cu" signal "IN2")
		(12 "In5.Cu" signal "GND2")
		(14 "In6.Cu" signal "IN3")
		(16 "In7.Cu" signal "GND3")
		(18 "In8.Cu" signal "VCC")
		(20 "In9.Cu" signal "VCC1")
		(22 "In10.Cu" signal "GND4")
		(24 "In11.Cu" signal "IN4")
		(26 "In12.Cu" signal "GND5")
		(28 "In13.Cu" signal "IN5")
		(30 "In14.Cu" signal "GND6")
		(32 "In15.Cu" signal "IN6")
		(34 "In16.Cu" signal "GND7")
		(2 "B.Cu" signal "BOTTOM")
		(9 "F.Adhes" user "F.Adhesive")
		(11 "B.Adhes" user "B.Adhesive")
		(13 "F.Paste" user "Package Geometry/Pastemask Top")
		(15 "B.Paste" user "Package Geometry/Pastemask Bottom")
		(5 "F.SilkS" user "Ref Des/Silkscreen Top")
		(7 "B.SilkS" user "Ref Des/Silkscreen Bottom")
		(1 "F.Mask" user "Board Geometry/Soldermask Top")
		(3 "B.Mask" user "Board Geometry/Soldermask Bottom")
		(17 "Dwgs.User" user "User.Drawings")
		(19 "Cmts.User" user "User.Comments")
		(21 "Eco1.User" user "User.Eco1")
		(23 "Eco2.User" user "User.Eco2")
		(25 "Edge.Cuts" user "Board Geometry/Outline")
		(27 "Margin" user)
		(31 "F.CrtYd" user "Package Geometry/Place Bound Top")
		(29 "B.CrtYd" user "Package Geometry/Place Bound Bottom")
		(35 "F.Fab" user "Ref Des/Assembly Top")
		(33 "B.Fab" user "Ref Des/Assembly Bottom")
	)
	(footprint ""
		(layer "B.Cu")
		(at 85.9282 -338.137246 -90)
		(property "Reference" "PR293"
			(at 0 0 90)
			(layer "B.SilkS")
			(hide yes)
			(effects
				(font
					(size 1.27 1.27)
				)
				(justify mirror)
			)
		)
		(property "Value" ""
			(at 0 0 90)
			(layer "B.Fab")
			(effects
				(font
					(size 1.27 1.27)
				)
				(justify mirror)
			)
		)
		(duplicate_pad_numbers_are_jumpers no)
		(fp_line
			(start -0.7874 0.4064)
			(end 0.7874 0.4064)
			(stroke
				(width 0.1524)
				(type default)
			)
			(layer "B.SilkS")
		)
		(fp_line
			(start 0.7874 0.4064)
			(end 0.7874 -0.4064)
			(stroke
				(width 0.1524)
				(type default)
			)
			(layer "B.SilkS")
		)
		(fp_line
			(start -0.7874 -0.4064)
			(end -0.7874 0.4064)
			(stroke
				(width 0.1524)
				(type default)
			)
			(layer "B.SilkS")
		)
		(fp_line
			(start 0.7874 -0.4064)
			(end -0.7874 -0.4064)
			(stroke
				(width 0.1524)
				(type default)
			)
			(layer "B.SilkS")
		)
		(fp_line
			(start -0.67945 0.3048)
			(end -0.120396 0.3048)
			(stroke
				(width 0.1)
				(type default)
			)
			(layer "B.Fab")
		)
		(fp_line
			(start -0.120396 0.3048)
			(end -0.120396 0.2794)
			(stroke
				(width 0.1)
				(type default)
			)
			(layer "B.Fab")
		)
		(fp_line
			(start 0.12065 0.3048)
			(end 0.67945 0.3048)
			(stroke
				(width 0.1)
				(type default)
			)
			(layer "B.Fab")
		)
		(fp_line
			(start 0.67945 0.3048)
			(end 0.67945 -0.305054)
			(stroke
				(width 0.1)
				(type default)
			)
			(layer "B.Fab")
		)
		(fp_line
			(start -0.120396 0.2794)
			(end 0.12065 0.2794)
			(stroke
				(width 0.1)
				(type default)
			)
			(layer "B.Fab")
		)
		(fp_line
			(start 0.12065 0.2794)
			(end 0.12065 0.3048)
			(stroke
				(width 0.1)
				(type default)
			)
			(layer "B.Fab")
		)
		(fp_line
			(start -0.12065 -0.2794)
			(end -0.12065 -0.3048)
			(stroke
				(width 0.1)
				(type default)
			)
			(layer "B.Fab")
		)
		(fp_line
			(start 0.12065 -0.2794)
			(end -0.12065 -0.2794)
			(stroke
				(width 0.1)
				(type default)
			)
			(layer "B.Fab")
		)
		(fp_line
			(start -0.67945 -0.3048)
			(end -0.67945 0.3048)
			(stroke
				(width 0.1)
				(type default)
			)
			(layer "B.Fab")
		)
		(fp_line
			(start -0.12065 -0.3048)
			(end -0.67945 -0.3048)
			(stroke
				(width 0.1)
				(type default)
			)
			(layer "B.Fab")
		)
		(fp_line
			(start 0.12065 -0.305054)
			(end 0.12065 -0.2794)
			(stroke
				(width 0.1)
				(type default)
			)
			(layer "B.Fab")
		)
		(fp_line
			(start 0.67945 -0.305054)
			(end 0.12065 -0.305054)
			(stroke
				(width 0.1)
				(type default)
			)
			(layer "B.Fab")
		)
		(pad "1" smd circle
			(at 0.40005 0 90)
			(size 0 0)
			(layers "B.Cu" "B.Mask" "B.Paste")
			(net "PVCCIN_CPU1_PVCC")
		)
		(pad "2" smd circle
			(at -0.40005 0 90)
			(size 0 0)
			(layers "B.Cu" "B.Mask" "B.Paste")
			(net "PVCCIN_CPU1_VDD6")
		)
	)
	(footprint ""
		(layer "B.Cu")
		(at 17.779492 -97.342198 90)
		(property "Reference" "C2040"
			(at 0 0 90)
			(layer "B.SilkS")
			(hide yes)
			(effects
				(font
					(size 1.27 1.27)
				)
				(justify mirror)
			)
		)
		(property "Value" ""
			(at 0 0 90)
			(layer "B.Fab")
			(effects
				(font
					(size 1.27 1.27)
				)
				(justify mirror)
			)
		)
		(duplicate_pad_numbers_are_jumpers no)
		(fp_line
			(start 0.7874 -0.4064)
			(end -0.7874 -0.4064)
			(stroke
				(width 0.1524)
				(type default)
			)
			(layer "B.SilkS")
		)
		(fp_line
			(start -0.7874 -0.4064)
			(end -0.7874 0.4064)
			(stroke
				(width 0.1524)
				(type default)
			)
			(layer "B.SilkS")
		)
		(fp_line
			(start 0.7874 0.4064)
			(end 0.7874 -0.4064)
			(stroke
				(width 0.1524)
				(type default)
			)
			(layer "B.SilkS")
		)
		(fp_line
			(start -0.7874 0.4064)
			(end 0.7874 0.4064)
			(stroke
				(width 0.1524)
				(type default)
			)
			(layer "B.SilkS")
		)
		(fp_line
			(start 0.67945 -0.305054)
			(end 0.12065 -0.305054)
			(stroke
				(width 0.1)
				(type default)
			)
			(layer "B.Fab")
		)
		(fp_line
			(start 0.12065 -0.305054)
			(end 0.12065 -0.2794)
			(stroke
				(width 0.1)
				(type default)
			)
			(layer "B.Fab")
		)
		(fp_line
			(start -0.12065 -0.3048)
			(end -0.67945 -0.3048)
			(stroke
				(width 0.1)
				(type default)
			)
			(layer "B.Fab")
		)
		(fp_line
			(start -0.67945 -0.3048)
			(end -0.67945 0.3048)
			(stroke
				(width 0.1)
				(type default)
			)
			(layer "B.Fab")
		)
		(fp_line
			(start 0.12065 -0.2794)
			(end -0.12065 -0.2794)
			(stroke
				(width 0.1)
				(type default)
			)
			(layer "B.Fab")
		)
		(fp_line
			(start -0.12065 -0.2794)
			(end -0.12065 -0.3048)
			(stroke
				(width 0.1)
				(type default)
			)
			(layer "B.Fab")
		)
		(fp_line
			(start 0.12065 0.2794)
			(end 0.12065 0.3048)
			(stroke
				(width 0.1)
				(type default)
			)
			(layer "B.Fab")
		)
		(fp_line
			(start -0.120396 0.2794)
			(end 0.12065 0.2794)
			(stroke
				(width 0.1)
				(type default)
			)
			(layer "B.Fab")
		)
		(fp_line
			(start 0.67945 0.3048)
			(end 0.67945 -0.305054)
			(stroke
				(width 0.1)
				(type default)
			)
			(layer "B.Fab")
		)
		(fp_line
			(start 0.12065 0.3048)
			(end 0.67945 0.3048)
			(stroke
				(width 0.1)
				(type default)
			)
			(layer "B.Fab")
		)
		(fp_line
			(start -0.120396 0.3048)
			(end -0.120396 0.2794)
			(stroke
				(width 0.1)
				(type default)
			)
			(layer "B.Fab")
		)
		(fp_line
			(start -0.67945 0.3048)
			(end -0.120396 0.3048)
			(stroke
				(width 0.1)
				(type default)
			)
			(layer "B.Fab")
		)
		(pad "1" smd circle
			(at 0.40005 0 270)
			(size 0 0)
			(layers "B.Cu" "B.Mask" "B.Paste")
			(net "P3V3_AUX_USB_HUB")
		)
		(pad "2" smd circle
			(at -0.40005 0 270)
			(size 0 0)
			(layers "B.Cu" "B.Mask" "B.Paste")
			(net "GND")
		)
	)
)
